(kicad_pcb
	(version 20260206)
	(generator "pcbnew")
	(generator_version "10.0")
	(general
		(thickness 1.6)
		(legacy_teardrops no)
	)
	(paper "A4")
	(title_block
		(title "12092022_DA0F0TFB6D0_F0T_FAN_BOARD_MP5048_D_brd_v02_OCP.brd")
		(comment 1 "Grand Teton / footprints 168-172 of 924")
	)
	(layers
		(0 "F.Cu" signal "TOP")
		(4 "In1.Cu" signal "GND")
		(6 "In2.Cu" signal "IN1")
		(8 "In3.Cu" signal "IN2")
		(10 "In4.Cu" signal "GND1")
		(2 "B.Cu" signal "BOTTOM")
		(9 "F.Adhes" user "F.Adhesive")
		(11 "B.Adhes" user "B.Adhesive")
		(13 "F.Paste" user "Package Geometry/Pastemask Top")
		(15 "B.Paste" user "Package Geometry/Pastemask Bottom")
		(5 "F.SilkS" user "Ref Des/Silkscreen Top")
		(7 "B.SilkS" user "Ref Des/Silkscreen Bottom")
		(1 "F.Mask" user "Board Geometry/Soldermask Top")
		(3 "B.Mask" user "Board Geometry/Soldermask Bottom")
		(17 "Dwgs.User" user "User.Drawings")
		(19 "Cmts.User" user "User.Comments")
		(21 "Eco1.User" user "User.Eco1")
		(23 "Eco2.User" user "User.Eco2")
		(25 "Edge.Cuts" user "Board Geometry/Outline")
		(27 "Margin" user)
		(31 "F.CrtYd" user "Package Geometry/Place Bound Top")
		(29 "B.CrtYd" user "Package Geometry/Place Bound Bottom")
		(35 "F.Fab" user "Ref Des/Assembly Top")
		(33 "B.Fab" user "Ref Des/Assembly Bottom")
	)
	(footprint ""
		(layer "F.Cu")
		(at 33.274 -102.546912 180)
		(property "Reference" "R5331"
			(at 0 0 180)
			(layer "F.SilkS")
			(hide yes)
			(effects
				(font
					(size 1.27 1.27)
				)
			)
		)
		(property "Value" ""
			(at 0 0 180)
			(layer "F.Fab")
			(effects
				(font
					(size 1.27 1.27)
				)
			)
		)
		(duplicate_pad_numbers_are_jumpers no)
		(fp_line
			(start 0.7874 0.4064)
			(end -0.7874 0.4064)
			(stroke
				(width 0.1524)
				(type default)
			)
			(layer "F.SilkS")
		)
		(fp_line
			(start 0.7874 -0.4064)
			(end 0.7874 0.4064)
			(stroke
				(width 0.1524)
				(type default)
			)
			(layer "F.SilkS")
		)
		(fp_line
			(start -0.7874 0.4064)
			(end -0.7874 -0.4064)
			(stroke
				(width 0.1524)
				(type default)
			)
			(layer "F.SilkS")
		)
		(fp_line
			(start -0.7874 -0.4064)
			(end 0.7874 -0.4064)
			(stroke
				(width 0.1524)
				(type default)
			)
			(layer "F.SilkS")
		)
		(fp_line
			(start 0.67945 0.3048)
			(end 0.120396 0.3048)
			(stroke
				(width 0.1)
				(type default)
			)
			(layer "F.Fab")
		)
		(fp_line
			(start 0.67945 -0.3048)
			(end 0.67945 0.3048)
			(stroke
				(width 0.1)
				(type default)
			)
			(layer "F.Fab")
		)
		(fp_line
			(start 0.12065 -0.2794)
			(end 0.12065 -0.3048)
			(stroke
				(width 0.1)
				(type default)
			)
			(layer "F.Fab")
		)
		(fp_line
			(start 0.12065 -0.3048)
			(end 0.67945 -0.3048)
			(stroke
				(width 0.1)
				(type default)
			)
			(layer "F.Fab")
		)
		(fp_line
			(start 0.120396 0.3048)
			(end 0.120396 0.2794)
			(stroke
				(width 0.1)
				(type default)
			)
			(layer "F.Fab")
		)
		(fp_line
			(start 0.120396 0.2794)
			(end -0.12065 0.2794)
			(stroke
				(width 0.1)
				(type default)
			)
			(layer "F.Fab")
		)
		(fp_line
			(start -0.12065 0.3048)
			(end -0.67945 0.3048)
			(stroke
				(width 0.1)
				(type default)
			)
			(layer "F.Fab")
		)
		(fp_line
			(start -0.12065 0.2794)
			(end -0.12065 0.3048)
			(stroke
				(width 0.1)
				(type default)
			)
			(layer "F.Fab")
		)
		(fp_line
			(start -0.12065 -0.2794)
			(end 0.12065 -0.2794)
			(stroke
				(width 0.1)
				(type default)
			)
			(layer "F.Fab")
		)
		(fp_line
			(start -0.12065 -0.305054)
			(end -0.12065 -0.2794)
			(stroke
				(width 0.1)
				(type default)
			)
			(layer "F.Fab")
		)
		(fp_line
			(start -0.67945 0.3048)
			(end -0.67945 -0.305054)
			(stroke
				(width 0.1)
				(type default)
			)
			(layer "F.Fab")
		)
		(fp_line
			(start -0.67945 -0.305054)
			(end -0.12065 -0.305054)
			(stroke
				(width 0.1)
				(type default)
			)
			(layer "F.Fab")
		)
		(pad "1" smd rect
			(at -0.40005 0)
			(size 0.4572 0.508)
			(layers "F.Cu" "F.Mask" "F.Paste")
			(net "FAN_2_TACH_OL_R")
		)
		(pad "2" smd rect
			(at 0.40005 0)
			(size 0.4572 0.508)
			(layers "F.Cu" "F.Mask" "F.Paste")
			(net "FAN_2_TACH_OL")
		)
	)
	(footprint ""
		(layer "F.Cu")
		(at 33.02 -301.752 180)
		(property "Reference" "R5302"
			(at 0 0 180)
			(layer "F.SilkS")
			(hide yes)
			(effects
				(font
					(size 1.27 1.27)
				)
			)
		)
		(property "Value" ""
			(at 0 0 180)
			(layer "F.Fab")
			(effects
				(font
					(size 1.27 1.27)
				)
			)
		)
		(duplicate_pad_numbers_are_jumpers no)
		(fp_line
			(start 0.7874 0.4064)
			(end -0.7874 0.4064)
			(stroke
				(width 0.1524)
				(type default)
			)
			(layer "F.SilkS")
		)
		(fp_line
			(start 0.7874 -0.4064)
			(end 0.7874 0.4064)
			(stroke
				(width 0.1524)
				(type default)
			)
			(layer "F.SilkS")
		)
		(fp_line
			(start -0.7874 0.4064)
			(end -0.7874 -0.4064)
			(stroke
				(width 0.1524)
				(type default)
			)
			(layer "F.SilkS")
		)
		(fp_line
			(start -0.7874 -0.4064)
			(end 0.7874 -0.4064)
			(stroke
				(width 0.1524)
				(type default)
			)
			(layer "F.SilkS")
		)
		(fp_line
			(start 0.67945 0.3048)
			(end 0.120396 0.3048)
			(stroke
				(width 0.1)
				(type default)
			)
			(layer "F.Fab")
		)
		(fp_line
			(start 0.67945 -0.3048)
			(end 0.67945 0.3048)
			(stroke
				(width 0.1)
				(type default)
			)
			(layer "F.Fab")
		)
		(fp_line
			(start 0.12065 -0.2794)
			(end 0.12065 -0.3048)
			(stroke
				(width 0.1)
				(type default)
			)
			(layer "F.Fab")
		)
		(fp_line
			(start 0.12065 -0.3048)
			(end 0.67945 -0.3048)
			(stroke
				(width 0.1)
				(type default)
			)
			(layer "F.Fab")
		)
		(fp_line
			(start 0.120396 0.3048)
			(end 0.120396 0.2794)
			(stroke
				(width 0.1)
				(type default)
			)
			(layer "F.Fab")
		)
		(fp_line
			(start 0.120396 0.2794)
			(end -0.12065 0.2794)
			(stroke
				(width 0.1)
				(type default)
			)
			(layer "F.Fab")
		)
		(fp_line
			(start -0.12065 0.3048)
			(end -0.67945 0.3048)
			(stroke
				(width 0.1)
				(type default)
			)
			(layer "F.Fab")
		)
		(fp_line
			(start -0.12065 0.2794)
			(end -0.12065 0.3048)
			(stroke
				(width 0.1)
				(type default)
			)
			(layer "F.Fab")
		)
		(fp_line
			(start -0.12065 -0.2794)
			(end 0.12065 -0.2794)
			(stroke
				(width 0.1)
				(type default)
			)
			(layer "F.Fab")
		)
		(fp_line
			(start -0.12065 -0.305054)
			(end -0.12065 -0.2794)
			(stroke
				(width 0.1)
				(type default)
			)
			(layer "F.Fab")
		)
		(fp_line
			(start -0.67945 0.3048)
			(end -0.67945 -0.305054)
			(stroke
				(width 0.1)
				(type default)
			)
			(layer "F.Fab")
		)
		(fp_line
			(start -0.67945 -0.305054)
			(end -0.12065 -0.305054)
			(stroke
				(width 0.1)
				(type default)
			)
			(layer "F.Fab")
		)
		(pad "1" smd rect
			(at -0.40005 0)
			(size 0.4572 0.508)
			(layers "F.Cu" "F.Mask" "F.Paste")
			(net "FAN_0_TACH_IL_R")
		)
		(pad "2" smd rect
			(at 0.40005 0)
			(size 0.4572 0.508)
			(layers "F.Cu" "F.Mask" "F.Paste")
			(net "FAN_0_TACH_IL")
		)
	)
	(footprint ""
		(layer "F.Cu")
		(at 36.322 -171.577 180)
		(property "Reference" "U8"
			(at -0.889 -4.72567 0)
			(unlocked yes)
			(layer "F.SilkS")
			(effects
				(font
					(size 0.7874 0.5842)
					(thickness 0.1524)
				)
				(justify left)
			)
		)
		(property "Value" ""
			(at 0 0 180)
			(layer "F.Fab")
			(effects
				(font
					(size 1.27 1.27)
				)
			)
		)
		(duplicate_pad_numbers_are_jumpers no)
		(fp_line
			(start 2.0066 3.9624)
			(end -2.0066 3.9624)
			(stroke
				(width 0.1524)
				(type default)
			)
			(layer "F.SilkS")
		)
		(fp_line
			(start 2.0066 -3.9624)
			(end 2.0066 3.9624)
			(stroke
				(width 0.1524)
				(type default)
			)
			(layer "F.SilkS")
		)
		(fp_line
			(start 0.5842 -3.9624)
			(end 2.0066 -3.9624)
			(stroke
				(width 0.1524)
				(type default)
			)
			(layer "F.SilkS")
		)
		(fp_line
			(start 0 -3.3782)
			(end 0.5842 -3.9624)
			(stroke
				(width 0.1524)
				(type default)
			)
			(layer "F.SilkS")
		)
		(fp_line
			(start -0.5842 -3.9624)
			(end 0 -3.3782)
			(stroke
				(width 0.1524)
				(type default)
			)
			(layer "F.SilkS")
		)
		(fp_line
			(start -2.0066 3.9624)
			(end -2.0066 -3.9624)
			(stroke
				(width 0.1524)
				(type default)
			)
			(layer "F.SilkS")
		)
		(fp_line
			(start -2.0066 -3.9624)
			(end -0.5842 -3.9624)
			(stroke
				(width 0.1524)
				(type default)
			)
			(layer "F.SilkS")
		)
		(fp_poly
			(pts
				(xy -3.8862 -3.570986) (xy -4.6482 -3.189986) (xy -4.6482 -3.951986)
			)
			(stroke
				(width 0)
				(type default)
			)
			(fill yes)
			(layer "F.SilkS")
		)
		(fp_line
			(start 3.7211 3.80365)
			(end 3.7211 -3.80365)
			(stroke
				(width 0.1)
				(type default)
			)
			(layer "F.Fab")
		)
		(fp_line
			(start 3.7211 -3.80365)
			(end 2.2479 -3.80365)
			(stroke
				(width 0.1)
				(type default)
			)
			(layer "F.Fab")
		)
		(fp_line
			(start 2.2479 3.9624)
			(end 2.2479 3.80365)
			(stroke
				(width 0.1)
				(type default)
			)
			(layer "F.Fab")
		)
		(fp_line
			(start 2.2479 3.80365)
			(end 3.7211 3.80365)
			(stroke
				(width 0.1)
				(type default)
			)
			(layer "F.Fab")
		)
		(fp_line
			(start 2.2479 -3.80365)
			(end 2.2479 -3.974846)
			(stroke
				(width 0.1)
				(type default)
			)
			(layer "F.Fab")
		)
		(fp_line
			(start 2.2479 -3.974846)
			(end -2.2479 -3.974846)
			(stroke
				(width 0.1)
				(type default)
			)
			(layer "F.Fab")
		)
		(fp_line
			(start -2.2479 3.9624)
			(end 2.2479 3.9624)
			(stroke
				(width 0.1)
				(type default)
			)
			(layer "F.Fab")
		)
		(fp_line
			(start -2.2479 3.80365)
			(end -2.2479 3.9624)
			(stroke
				(width 0.1)
				(type default)
			)
			(layer "F.Fab")
		)
		(fp_line
			(start -2.2479 -3.80365)
			(end -3.724402 -3.80365)
			(stroke
				(width 0.1)
				(type default)
			)
			(layer "F.Fab")
		)
		(fp_line
			(start -2.2479 -3.974846)
			(end -2.2479 -3.80365)
			(stroke
				(width 0.1)
				(type default)
			)
			(layer "F.Fab")
		)
		(fp_line
			(start -3.7211 -3.34645)
			(end -3.7211 -3.80365)
			(stroke
				(width 0.1)
				(type default)
			)
			(layer "F.Fab")
		)
		(fp_line
			(start -3.724402 3.80365)
			(end -2.2479 3.80365)
			(stroke
				(width 0.1)
				(type default)
			)
			(layer "F.Fab")
		)
		(fp_line
			(start -3.724402 -3.80365)
			(end -3.724402 3.80365)
			(stroke
				(width 0.1)
				(type default)
			)
			(layer "F.Fab")
		)
		(fp_poly
			(pts
				(xy -3.8862 -3.570986) (xy -4.6482 -3.189986) (xy -4.6482 -3.951986)
			)
			(stroke
				(width 0)
				(type default)
			)
			(fill yes)
			(layer "F.Fab")
		)
		(pad "1" smd rect
			(at -2.921 -3.57505 90)
			(size 0.3556 1.4986)
			(layers "F.Cu" "F.Mask" "F.Paste")
			(net "PCA9552_MB1_A0")
		)
		(pad "2" smd rect
			(at -2.921 -2.925064 90)
			(size 0.3556 1.4986)
			(layers "F.Cu" "F.Mask" "F.Paste")
			(net "PCA9552_MB1_A1")
		)
		(pad "3" smd rect
			(at -2.921 -2.275078 90)
			(size 0.3556 1.4986)
			(layers "F.Cu" "F.Mask" "F.Paste")
			(net "PCA9552_MB1_A2")
		)
		(pad "4" smd rect
			(at -2.921 -1.625092 90)
			(size 0.3556 1.4986)
			(layers "F.Cu" "F.Mask" "F.Paste")
			(net "FAN_0_OK_LED")
		)
		(pad "5" smd rect
			(at -2.921 -0.975106 90)
			(size 0.3556 1.4986)
			(layers "F.Cu" "F.Mask" "F.Paste")
			(net "FAN_0_FAIL_LED")
		)
		(pad "6" smd rect
			(at -2.921 -0.32512 90)
			(size 0.3556 1.4986)
			(layers "F.Cu" "F.Mask" "F.Paste")
			(net "FAN_1_OK_LED")
		)
		(pad "7" smd rect
			(at -2.921 0.32512 90)
			(size 0.3556 1.4986)
			(layers "F.Cu" "F.Mask" "F.Paste")
			(net "FAN_1_FAIL_LED")
		)
		(pad "8" smd rect
			(at -2.921 0.975106 90)
			(size 0.3556 1.4986)
			(layers "F.Cu" "F.Mask" "F.Paste")
			(net "FAN_2_OK_LED")
		)
		(pad "9" smd rect
			(at -2.921 1.625092 90)
			(size 0.3556 1.4986)
			(layers "F.Cu" "F.Mask" "F.Paste")
			(net "FAN_2_FAIL_LED")
		)
		(pad "10" smd rect
			(at -2.921 2.275078 90)
			(size 0.3556 1.4986)
			(layers "F.Cu" "F.Mask" "F.Paste")
			(net "FAN_3_OK_LED")
		)
		(pad "11" smd rect
			(at -2.921 2.925064 90)
			(size 0.3556 1.4986)
			(layers "F.Cu" "F.Mask" "F.Paste")
			(net "FAN_3_FAIL_LED")
		)
		(pad "12" smd rect
			(at -2.921 3.57505 90)
			(size 0.3556 1.4986)
			(layers "F.Cu" "F.Mask" "F.Paste")
			(net "GND")
		)
		(pad "13" smd rect
			(at 2.921 3.57505 90)
			(size 0.3556 1.4986)
			(layers "F.Cu" "F.Mask" "F.Paste")
			(net "FAN_4_OK_LED")
		)
		(pad "14" smd rect
			(at 2.921 2.925064 90)
			(size 0.3556 1.4986)
			(layers "F.Cu" "F.Mask" "F.Paste")
			(net "FAN_4_FAIL_LED")
		)
		(pad "15" smd rect
			(at 2.921 2.275078 90)
			(size 0.3556 1.4986)
			(layers "F.Cu" "F.Mask" "F.Paste")
			(net "FAN_5_OK_LED")
		)
		(pad "16" smd rect
			(at 2.921 1.625092 90)
			(size 0.3556 1.4986)
			(layers "F.Cu" "F.Mask" "F.Paste")
			(net "FAN_5_FAIL_LED")
		)
		(pad "17" smd rect
			(at 2.921 0.975106 90)
			(size 0.3556 1.4986)
			(layers "F.Cu" "F.Mask" "F.Paste")
			(net "FAN_6_OK_LED")
		)
		(pad "18" smd rect
			(at 2.921 0.32512 90)
			(size 0.3556 1.4986)
			(layers "F.Cu" "F.Mask" "F.Paste")
			(net "FAN_6_FAIL_LED")
		)
		(pad "19" smd rect
			(at 2.921 -0.32512 90)
			(size 0.3556 1.4986)
			(layers "F.Cu" "F.Mask" "F.Paste")
			(net "FAN_7_OK_LED")
		)
		(pad "20" smd rect
			(at 2.921 -0.975106 90)
			(size 0.3556 1.4986)
			(layers "F.Cu" "F.Mask" "F.Paste")
			(net "FAN_7_FAIL_LED")
		)
		(pad "21" smd rect
			(at 2.921 -1.625092 90)
			(size 0.3556 1.4986)
			(layers "F.Cu" "F.Mask" "F.Paste")
			(net "PU_U8_PIN2")
		)
		(pad "22" smd rect
			(at 2.921 -2.275078 90)
			(size 0.3556 1.4986)
			(layers "F.Cu" "F.Mask" "F.Paste")
			(net "SMB_PDBV_FAN_R1_IOX_SCL")
		)
		(pad "23" smd rect
			(at 2.921 -2.925064 90)
			(size 0.3556 1.4986)
			(layers "F.Cu" "F.Mask" "F.Paste")
			(net "SMB_PDBV_FAN_R1_IOX_SDA")
		)
		(pad "24" smd rect
			(at 2.921 -3.57505 90)
			(size 0.3556 1.4986)
			(layers "F.Cu" "F.Mask" "F.Paste")
			(net "P3V3_AUX")
		)
	)
	(footprint ""
		(layer "F.Cu")
		(at 40.127428 -252.386846 180)
		(property "Reference" "C2066"
			(at 0 0 180)
			(layer "F.SilkS")
			(hide yes)
			(effects
				(font
					(size 1.27 1.27)
				)
			)
		)
		(property "Value" ""
			(at 0 0 180)
			(layer "F.Fab")
			(effects
				(font
					(size 1.27 1.27)
				)
			)
		)
		(duplicate_pad_numbers_are_jumpers no)
		(fp_line
			(start 0.7874 0.4064)
			(end -0.7874 0.4064)
			(stroke
				(width 0.1524)
				(type default)
			)
			(layer "F.SilkS")
		)
		(fp_line
			(start 0.7874 -0.4064)
			(end 0.7874 0.4064)
			(stroke
				(width 0.1524)
				(type default)
			)
			(layer "F.SilkS")
		)
		(fp_line
			(start -0.7874 0.4064)
			(end -0.7874 -0.4064)
			(stroke
				(width 0.1524)
				(type default)
			)
			(layer "F.SilkS")
		)
		(fp_line
			(start -0.7874 -0.4064)
			(end 0.7874 -0.4064)
			(stroke
				(width 0.1524)
				(type default)
			)
			(layer "F.SilkS")
		)
		(fp_line
			(start 0.67945 0.3048)
			(end 0.120396 0.3048)
			(stroke
				(width 0.1)
				(type default)
			)
			(layer "F.Fab")
		)
		(fp_line
			(start 0.67945 -0.3048)
			(end 0.67945 0.3048)
			(stroke
				(width 0.1)
				(type default)
			)
			(layer "F.Fab")
		)
		(fp_line
			(start 0.12065 -0.2794)
			(end 0.12065 -0.3048)
			(stroke
				(width 0.1)
				(type default)
			)
			(layer "F.Fab")
		)
		(fp_line
			(start 0.12065 -0.3048)
			(end 0.67945 -0.3048)
			(stroke
				(width 0.1)
				(type default)
			)
			(layer "F.Fab")
		)
		(fp_line
			(start 0.120396 0.3048)
			(end 0.120396 0.2794)
			(stroke
				(width 0.1)
				(type default)
			)
			(layer "F.Fab")
		)
		(fp_line
			(start 0.120396 0.2794)
			(end -0.12065 0.2794)
			(stroke
				(width 0.1)
				(type default)
			)
			(layer "F.Fab")
		)
		(fp_line
			(start -0.12065 0.3048)
			(end -0.67945 0.3048)
			(stroke
				(width 0.1)
				(type default)
			)
			(layer "F.Fab")
		)
		(fp_line
			(start -0.12065 0.2794)
			(end -0.12065 0.3048)
			(stroke
				(width 0.1)
				(type default)
			)
			(layer "F.Fab")
		)
		(fp_line
			(start -0.12065 -0.2794)
			(end 0.12065 -0.2794)
			(stroke
				(width 0.1)
				(type default)
			)
			(layer "F.Fab")
		)
		(fp_line
			(start -0.12065 -0.305054)
			(end -0.12065 -0.2794)
			(stroke
				(width 0.1)
				(type default)
			)
			(layer "F.Fab")
		)
		(fp_line
			(start -0.67945 0.3048)
			(end -0.67945 -0.305054)
			(stroke
				(width 0.1)
				(type default)
			)
			(layer "F.Fab")
		)
		(fp_line
			(start -0.67945 -0.305054)
			(end -0.12065 -0.305054)
			(stroke
				(width 0.1)
				(type default)
			)
			(layer "F.Fab")
		)
		(pad "1" smd circle
			(at -0.40005 0 180)
			(size 0 0)
			(layers "F.Cu" "F.Mask" "F.Paste")
			(net "P3V3_AUX")
		)
		(pad "2" smd circle
			(at 0.40005 0 180)
			(size 0 0)
			(layers "F.Cu" "F.Mask" "F.Paste")
			(net "GND")
		)
	)
	(footprint ""
		(layer "F.Cu")
		(at 44.831 -314.071)
		(property "Reference" "R5648"
			(at 0 0 0)
			(layer "F.SilkS")
			(hide yes)
			(effects
				(font
					(size 1.27 1.27)
				)
			)
		)
		(property "Value" ""
			(at 0 0 0)
			(layer "F.Fab")
			(effects
				(font
					(size 1.27 1.27)
				)
			)
		)
		(duplicate_pad_numbers_are_jumpers no)
		(fp_line
			(start -0.7874 -0.4064)
			(end 0.7874 -0.4064)
			(stroke
				(width 0.1524)
				(type default)
			)
			(layer "F.SilkS")
		)
		(fp_line
			(start -0.7874 0.4064)
			(end -0.7874 -0.4064)
			(stroke
				(width 0.1524)
				(type default)
			)
			(layer "F.SilkS")
		)
		(fp_line
			(start 0.7874 -0.4064)
			(end 0.7874 0.4064)
			(stroke
				(width 0.1524)
				(type default)
			)
			(layer "F.SilkS")
		)
		(fp_line
			(start 0.7874 0.4064)
			(end -0.7874 0.4064)
			(stroke
				(width 0.1524)
				(type default)
			)
			(layer "F.SilkS")
		)
		(fp_line
			(start -0.67945 -0.305054)
			(end -0.12065 -0.305054)
			(stroke
				(width 0.1)
				(type default)
			)
			(layer "F.Fab")
		)
		(fp_line
			(start -0.67945 0.3048)
			(end -0.67945 -0.305054)
			(stroke
				(width 0.1)
				(type default)
			)
			(layer "F.Fab")
		)
		(fp_line
			(start -0.12065 -0.305054)
			(end -0.12065 -0.2794)
			(stroke
				(width 0.1)
				(type default)
			)
			(layer "F.Fab")
		)
		(fp_line
			(start -0.12065 -0.2794)
			(end 0.12065 -0.2794)
			(stroke
				(width 0.1)
				(type default)
			)
			(layer "F.Fab")
		)
		(fp_line
			(start -0.12065 0.2794)
			(end -0.12065 0.3048)
			(stroke
				(width 0.1)
				(type default)
			)
			(layer "F.Fab")
		)
		(fp_line
			(start -0.12065 0.3048)
			(end -0.67945 0.3048)
			(stroke
				(width 0.1)
				(type default)
			)
			(layer "F.Fab")
		)
		(fp_line
			(start 0.120396 0.2794)
			(end -0.12065 0.2794)
			(stroke
				(width 0.1)
				(type default)
			)
			(layer "F.Fab")
		)
		(fp_line
			(start 0.120396 0.3048)
			(end 0.120396 0.2794)
			(stroke
				(width 0.1)
				(type default)
			)
			(layer "F.Fab")
		)
		(fp_line
			(start 0.12065 -0.3048)
			(end 0.67945 -0.3048)
			(stroke
				(width 0.1)
				(type default)
			)
			(layer "F.Fab")
		)
		(fp_line
			(start 0.12065 -0.2794)
			(end 0.12065 -0.3048)
			(stroke
				(width 0.1)
				(type default)
			)
			(layer "F.Fab")
		)
		(fp_line
			(start 0.67945 -0.3048)
			(end 0.67945 0.3048)
			(stroke
				(width 0.1)
				(type default)
			)
			(layer "F.Fab")
		)
		(fp_line
			(start 0.67945 0.3048)
			(end 0.120396 0.3048)
			(stroke
				(width 0.1)
				(type default)
			)
			(layer "F.Fab")
		)
		(pad "1" smd rect
			(at -0.40005 0 180)
			(size 0.4572 0.508)
			(layers "F.Cu" "F.Mask" "F.Paste")
			(net "P12V_LED")
		)
		(pad "2" smd rect
			(at 0.40005 0 180)
			(size 0.4572 0.508)
			(layers "F.Cu" "F.Mask" "F.Paste")
			(net "U405_D1")
		)
	)
)
